#ISCELL
  mstr_misc dns *
  *
#ISCELL
  pure_quanta quanta_title_block_c *
  *
#ISCELL
  standard offpage *
  page151_i1
#ISCELL
  standard offpage *
  page151_i10
#ISCELL
  logical_power universal_gnd *
  page151_i11
#ISCELL
  logical_power universal_gnd *
  page151_i12
#CELL
  pure_quanta q_res *
  page151_i13
#ISCELL
  standard offpage *
  page151_i14
#CELL
  pure_quanta 74lvc1g126se7 *
  page151_i15
#ISCELL
  logical_power universal_gnd *
  page151_i16
#CELL
  pure_quanta q_res *
  page151_i17
#CELL
  pure_quanta q_res *
  page151_i19
#ISCELL
  standard offpage *
  page151_i2
#ISCELL
  logical_power universal_gnd *
  page151_i20
#CELL
  pure_quanta q_res *
  page151_i21
#CELL
  pure_quanta q_cap *
  page151_i22
#ISCELL
  logical_power universal_gnd *
  page151_i23
#ISCELL
  logical_power universal_power *
  page151_i24
#ISCELL
  standard offpage *
  page151_i25
#ISCELL
  standard offpage *
  page151_i26
#ISCELL
  standard offpage *
  page151_i27
#ISCELL
  standard offpage *
  page151_i28
#ISCELL
  logical_power universal_gnd *
  page151_i29
#CELL
  pure_quanta q_res *
  page151_i3
#CELL
  pure_quanta 74cbtlv3126pw *
  page151_i30
#ISCELL
  logical_power universal_gnd *
  page151_i31
#CELL
  pure_quanta q_cap *
  page151_i32
#ISCELL
  logical_power universal_power *
  page151_i33
#ISCELL
  standard offpage *
  page151_i34
#ISCELL
  standard offpage *
  page151_i35
#ISCELL
  standard offpage *
  page151_i36
#ISCELL
  standard offpage *
  page151_i37
#ISCELL
  logical_power universal_gnd *
  page151_i38
#CELL
  pure_quanta 74cbtlv3126pw *
  page151_i39
#ISCELL
  standard offpage *
  page151_i4
#CELL
  pure_quanta q_cap *
  page151_i40
#ISCELL
  logical_power universal_gnd *
  page151_i41
#ISCELL
  logical_power universal_power *
  page151_i42
#CELL
  pure_quanta q_res *
  page151_i43
#ISCELL
  standard offpage *
  page151_i44
#ISCELL
  standard offpage *
  page151_i45
#ISCELL
  standard offpage *
  page151_i46
#ISCELL
  standard offpage *
  page151_i47
#ISCELL
  standard offpage *
  page151_i48
#ISCELL
  standard offpage *
  page151_i49
#CELL
  pure_quanta q_res *
  page151_i5
#CELL
  pure_quanta q_res *
  page151_i50
#ISCELL
  logical_power universal_gnd *
  page151_i51
#CELL
  pure_quanta q_res *
  page151_i52
#CELL
  pure_quanta q_res *
  page151_i53
#CELL
  pure_quanta q_res *
  page151_i54
#CELL
  pure_quanta q_res *
  page151_i55
#CELL
  pure_quanta q_res *
  page151_i56
#ISCELL
  standard offpage *
  page151_i57
#ISCELL
  standard offpage *
  page151_i58
#ISCELL
  standard offpage *
  page151_i59
#ISCELL
  logical_power universal_gnd *
  page151_i6
#ISCELL
  logical_power universal_gnd *
  page151_i60
#CELL
  pure_quanta q_res *
  page151_i61
#ISCELL
  standard offpage *
  page151_i62
#ISCELL
  standard offpage *
  page151_i63
#ISCELL
  standard offpage *
  page151_i64
#CELL
  pure_quanta q_res *
  page151_i65
#CELL
  pure_quanta q_res *
  page151_i66
#CELL
  pure_quanta q_res *
  page151_i67
#CELL
  pure_quanta q_res *
  page151_i68
#CELL
  pure_quanta q_res *
  page151_i69
#CELL
  pure_quanta 74lvc1g126se7 *
  page151_i7
#ISCELL
  standard offpage *
  page151_i70
#CELL
  pure_quanta q_res *
  page151_i71
#CELL
  pure_quanta q_res *
  page151_i72
#CELL
  pure_quanta q_res *
  page151_i73
#ISCELL
  standard offpage *
  page151_i74
#ISCELL
  standard offpage *
  page151_i75
#ISCELL
  standard offpage *
  page151_i76
#ISCELL
  standard offpage *
  page151_i77
#ISCELL
  standard offpage *
  page151_i78
#ISCELL
  standard offpage *
  page151_i79
#CELL
  pure_quanta q_cap *
  page151_i8
#CELL
  pure_quanta q_res *
  page151_i80
#CELL
  pure_quanta q_res *
  page151_i81
#ISCELL
  standard offpage *
  page151_i82
#CELL
  pure_quanta q_res *
  page151_i83
#ISCELL
  logical_power universal_power *
  page151_i9
